(kicad_pcb
	(version 20260206)
	(generator "pcbnew")
	(generator_version "10.0")
	(general
		(thickness 1.6)
		(legacy_teardrops no)
	)
	(paper "A4")
	(title_block
		(title "01162023_DA0F0TEBIF0_F0T_Expander_BD_F_brd_V02_OCP.brd")
		(comment 1 "Grand Teton / footprints 9080-9088 of 9728")
	)
	(layers
		(0 "F.Cu" signal "TOP")
		(4 "In1.Cu" signal "GND")
		(6 "In2.Cu" signal "VCC")
		(8 "In3.Cu" signal "VCC1")
		(10 "In4.Cu" signal "GND1")
		(12 "In5.Cu" signal "IN1")
		(14 "In6.Cu" signal "GND2")
		(16 "In7.Cu" signal "IN2")
		(18 "In8.Cu" signal "GND3")
		(20 "In9.Cu" signal "IN3")
		(22 "In10.Cu" signal "GND4")
		(24 "In11.Cu" signal "IN4")
		(26 "In12.Cu" signal "GND5")
		(28 "In13.Cu" signal "IN5")
		(30 "In14.Cu" signal "GND6")
		(32 "In15.Cu" signal "IN6")
		(34 "In16.Cu" signal "GND7")
		(2 "B.Cu" signal "BOTTOM")
		(9 "F.Adhes" user "F.Adhesive")
		(11 "B.Adhes" user "B.Adhesive")
		(13 "F.Paste" user "Package Geometry/Pastemask Top")
		(15 "B.Paste" user "Package Geometry/Pastemask Bottom")
		(5 "F.SilkS" user "Ref Des/Silkscreen Top")
		(7 "B.SilkS" user "Ref Des/Silkscreen Bottom")
		(1 "F.Mask" user "Board Geometry/Soldermask Top")
		(3 "B.Mask" user "Board Geometry/Soldermask Bottom")
		(17 "Dwgs.User" user "User.Drawings")
		(19 "Cmts.User" user "User.Comments")
		(21 "Eco1.User" user "User.Eco1")
		(23 "Eco2.User" user "User.Eco2")
		(25 "Edge.Cuts" user "Board Geometry/Outline")
		(27 "Margin" user)
		(31 "F.CrtYd" user "Package Geometry/Place Bound Top")
		(29 "B.CrtYd" user "Package Geometry/Place Bound Bottom")
		(35 "F.Fab" user "Ref Des/Assembly Top")
		(33 "B.Fab" user "Ref Des/Assembly Bottom")
	)
	(footprint ""
		(layer "B.Cu")
		(at 57.430162 -295.221914)
		(property "Reference" "C1101"
			(at 0 0 0)
			(layer "B.SilkS")
			(hide yes)
			(effects
				(font
					(size 1.27 1.27)
				)
				(justify mirror)
			)
		)
		(property "Value" ""
			(at 0 0 0)
			(layer "B.Fab")
			(effects
				(font
					(size 1.27 1.27)
				)
				(justify mirror)
			)
		)
		(duplicate_pad_numbers_are_jumpers no)
		(fp_line
			(start -1.2954 -0.5842)
			(end -1.2954 0.5842)
			(stroke
				(width 0.1524)
				(type default)
			)
			(layer "B.SilkS")
		)
		(fp_line
			(start -1.2954 0.5842)
			(end 1.2954 0.5842)
			(stroke
				(width 0.1524)
				(type default)
			)
			(layer "B.SilkS")
		)
		(fp_line
			(start 1.2954 -0.5842)
			(end -1.2954 -0.5842)
			(stroke
				(width 0.1524)
				(type default)
			)
			(layer "B.SilkS")
		)
		(fp_line
			(start 1.2954 0.5842)
			(end 1.2954 -0.5842)
			(stroke
				(width 0.1524)
				(type default)
			)
			(layer "B.SilkS")
		)
		(fp_line
			(start -1.1938 -0.4064)
			(end -1.1938 0.4064)
			(stroke
				(width 0.1)
				(type default)
			)
			(layer "B.Fab")
		)
		(fp_line
			(start -1.1938 0.4064)
			(end -0.8636 0.4064)
			(stroke
				(width 0.1)
				(type default)
			)
			(layer "B.Fab")
		)
		(fp_line
			(start -0.8636 -0.4572)
			(end -0.8636 -0.4064)
			(stroke
				(width 0.1)
				(type default)
			)
			(layer "B.Fab")
		)
		(fp_line
			(start -0.8636 -0.4064)
			(end -1.1938 -0.4064)
			(stroke
				(width 0.1)
				(type default)
			)
			(layer "B.Fab")
		)
		(fp_line
			(start -0.8636 0.4064)
			(end -0.8636 0.4572)
			(stroke
				(width 0.1)
				(type default)
			)
			(layer "B.Fab")
		)
		(fp_line
			(start -0.8636 0.4572)
			(end 0.8636 0.4572)
			(stroke
				(width 0.1)
				(type default)
			)
			(layer "B.Fab")
		)
		(fp_line
			(start 0.8636 -0.4572)
			(end -0.8636 -0.4572)
			(stroke
				(width 0.1)
				(type default)
			)
			(layer "B.Fab")
		)
		(fp_line
			(start 0.8636 -0.4064)
			(end 0.8636 -0.4572)
			(stroke
				(width 0.1)
				(type default)
			)
			(layer "B.Fab")
		)
		(fp_line
			(start 0.8636 0.4064)
			(end 1.1938 0.4064)
			(stroke
				(width 0.1)
				(type default)
			)
			(layer "B.Fab")
		)
		(fp_line
			(start 0.8636 0.4572)
			(end 0.8636 0.4064)
			(stroke
				(width 0.1)
				(type default)
			)
			(layer "B.Fab")
		)
		(fp_line
			(start 1.1938 -0.4064)
			(end 0.8636 -0.4064)
			(stroke
				(width 0.1)
				(type default)
			)
			(layer "B.Fab")
		)
		(fp_line
			(start 1.1938 0.4064)
			(end 1.1938 -0.4064)
			(stroke
				(width 0.1)
				(type default)
			)
			(layer "B.Fab")
		)
		(pad "1" smd rect
			(at 0.7366 0 270)
			(size 0.7112 0.8128)
			(layers "B.Cu" "B.Mask" "B.Paste")
			(net "P0V8_PEX0")
		)
		(pad "2" smd rect
			(at -0.7366 0 270)
			(size 0.7112 0.8128)
			(layers "B.Cu" "B.Mask" "B.Paste")
			(net "GND")
		)
	)
	(footprint ""
		(layer "B.Cu")
		(at 284.249876 -301.599854 -90)
		(property "Reference" "C1696"
			(at 0 0 90)
			(layer "B.SilkS")
			(hide yes)
			(effects
				(font
					(size 1.27 1.27)
				)
				(justify mirror)
			)
		)
		(property "Value" ""
			(at 0 0 90)
			(layer "B.Fab")
			(effects
				(font
					(size 1.27 1.27)
				)
				(justify mirror)
			)
		)
		(duplicate_pad_numbers_are_jumpers no)
		(fp_line
			(start -0.299974 0.150114)
			(end 0.299974 0.150114)
			(stroke
				(width 0.1)
				(type default)
			)
			(layer "B.Fab")
		)
		(fp_line
			(start 0.299974 0.150114)
			(end 0.299974 -0.150114)
			(stroke
				(width 0.1)
				(type default)
			)
			(layer "B.Fab")
		)
		(fp_line
			(start -0.299974 -0.150114)
			(end -0.299974 0.150114)
			(stroke
				(width 0.1)
				(type default)
			)
			(layer "B.Fab")
		)
		(fp_line
			(start 0.299974 -0.150114)
			(end -0.299974 -0.150114)
			(stroke
				(width 0.1)
				(type default)
			)
			(layer "B.Fab")
		)
		(pad "1" smd rect
			(at 0.2667 0 90)
			(size 0.3048 0.381)
			(layers "B.Cu" "B.Mask" "B.Paste")
			(net "P0V8_SERDES_VDDA_PEX2")
		)
		(pad "2" smd rect
			(at -0.2667 0 90)
			(size 0.3048 0.381)
			(layers "B.Cu" "B.Mask" "B.Paste")
			(net "GND")
		)
	)
	(footprint ""
		(layer "B.Cu")
		(at 57.749948 -290.199826 90)
		(property "Reference" "C1235"
			(at 0 0 90)
			(layer "B.SilkS")
			(hide yes)
			(effects
				(font
					(size 1.27 1.27)
				)
				(justify mirror)
			)
		)
		(property "Value" ""
			(at 0 0 90)
			(layer "B.Fab")
			(effects
				(font
					(size 1.27 1.27)
				)
				(justify mirror)
			)
		)
		(duplicate_pad_numbers_are_jumpers no)
		(fp_line
			(start 0.299974 -0.150114)
			(end -0.299974 -0.150114)
			(stroke
				(width 0.1)
				(type default)
			)
			(layer "B.Fab")
		)
		(fp_line
			(start -0.299974 -0.150114)
			(end -0.299974 0.150114)
			(stroke
				(width 0.1)
				(type default)
			)
			(layer "B.Fab")
		)
		(fp_line
			(start 0.299974 0.150114)
			(end 0.299974 -0.150114)
			(stroke
				(width 0.1)
				(type default)
			)
			(layer "B.Fab")
		)
		(fp_line
			(start -0.299974 0.150114)
			(end 0.299974 0.150114)
			(stroke
				(width 0.1)
				(type default)
			)
			(layer "B.Fab")
		)
		(pad "1" smd rect
			(at 0.2667 0 270)
			(size 0.3048 0.381)
			(layers "B.Cu" "B.Mask" "B.Paste")
			(net "P0V8_SERDES_VDDA_PEX0")
		)
		(pad "2" smd rect
			(at -0.2667 0 270)
			(size 0.3048 0.381)
			(layers "B.Cu" "B.Mask" "B.Paste")
			(net "GND")
		)
	)
	(footprint ""
		(layer "B.Cu")
		(at 223.533716 -193.759836 90)
		(property "Reference" "R468"
			(at 0 0 90)
			(layer "B.SilkS")
			(hide yes)
			(effects
				(font
					(size 1.27 1.27)
				)
				(justify mirror)
			)
		)
		(property "Value" ""
			(at 0 0 90)
			(layer "B.Fab")
			(effects
				(font
					(size 1.27 1.27)
				)
				(justify mirror)
			)
		)
		(duplicate_pad_numbers_are_jumpers no)
		(fp_line
			(start 0.7874 -0.4064)
			(end -0.7874 -0.4064)
			(stroke
				(width 0.1524)
				(type default)
			)
			(layer "B.SilkS")
		)
		(fp_line
			(start -0.7874 -0.4064)
			(end -0.7874 0.4064)
			(stroke
				(width 0.1524)
				(type default)
			)
			(layer "B.SilkS")
		)
		(fp_line
			(start 0.7874 0.4064)
			(end 0.7874 -0.4064)
			(stroke
				(width 0.1524)
				(type default)
			)
			(layer "B.SilkS")
		)
		(fp_line
			(start -0.7874 0.4064)
			(end 0.7874 0.4064)
			(stroke
				(width 0.1524)
				(type default)
			)
			(layer "B.SilkS")
		)
		(fp_line
			(start 0.67945 -0.305054)
			(end 0.12065 -0.305054)
			(stroke
				(width 0.1)
				(type default)
			)
			(layer "B.Fab")
		)
		(fp_line
			(start 0.12065 -0.305054)
			(end 0.12065 -0.2794)
			(stroke
				(width 0.1)
				(type default)
			)
			(layer "B.Fab")
		)
		(fp_line
			(start -0.12065 -0.3048)
			(end -0.67945 -0.3048)
			(stroke
				(width 0.1)
				(type default)
			)
			(layer "B.Fab")
		)
		(fp_line
			(start -0.67945 -0.3048)
			(end -0.67945 0.3048)
			(stroke
				(width 0.1)
				(type default)
			)
			(layer "B.Fab")
		)
		(fp_line
			(start 0.12065 -0.2794)
			(end -0.12065 -0.2794)
			(stroke
				(width 0.1)
				(type default)
			)
			(layer "B.Fab")
		)
		(fp_line
			(start -0.12065 -0.2794)
			(end -0.12065 -0.3048)
			(stroke
				(width 0.1)
				(type default)
			)
			(layer "B.Fab")
		)
		(fp_line
			(start 0.12065 0.2794)
			(end 0.12065 0.3048)
			(stroke
				(width 0.1)
				(type default)
			)
			(layer "B.Fab")
		)
		(fp_line
			(start -0.120396 0.2794)
			(end 0.12065 0.2794)
			(stroke
				(width 0.1)
				(type default)
			)
			(layer "B.Fab")
		)
		(fp_line
			(start 0.67945 0.3048)
			(end 0.67945 -0.305054)
			(stroke
				(width 0.1)
				(type default)
			)
			(layer "B.Fab")
		)
		(fp_line
			(start 0.12065 0.3048)
			(end 0.67945 0.3048)
			(stroke
				(width 0.1)
				(type default)
			)
			(layer "B.Fab")
		)
		(fp_line
			(start -0.120396 0.3048)
			(end -0.120396 0.2794)
			(stroke
				(width 0.1)
				(type default)
			)
			(layer "B.Fab")
		)
		(fp_line
			(start -0.67945 0.3048)
			(end -0.120396 0.3048)
			(stroke
				(width 0.1)
				(type default)
			)
			(layer "B.Fab")
		)
		(pad "1" smd circle
			(at 0.40005 0 270)
			(size 0 0)
			(layers "B.Cu" "B.Mask" "B.Paste")
			(net "SPI_BIC1_MISO_R1")
		)
		(pad "2" smd circle
			(at -0.40005 0 270)
			(size 0 0)
			(layers "B.Cu" "B.Mask" "B.Paste")
			(net "SPI_BIC1_MISO_R2")
		)
	)
	(footprint ""
		(layer "B.Cu")
		(at 286.624776 -297.79976 -90)
		(property "Reference" "C1663"
			(at 0 0 90)
			(layer "B.SilkS")
			(hide yes)
			(effects
				(font
					(size 1.27 1.27)
				)
				(justify mirror)
			)
		)
		(property "Value" ""
			(at 0 0 90)
			(layer "B.Fab")
			(effects
				(font
					(size 1.27 1.27)
				)
				(justify mirror)
			)
		)
		(duplicate_pad_numbers_are_jumpers no)
		(fp_line
			(start -0.299974 0.150114)
			(end 0.299974 0.150114)
			(stroke
				(width 0.1)
				(type default)
			)
			(layer "B.Fab")
		)
		(fp_line
			(start 0.299974 0.150114)
			(end 0.299974 -0.150114)
			(stroke
				(width 0.1)
				(type default)
			)
			(layer "B.Fab")
		)
		(fp_line
			(start -0.299974 -0.150114)
			(end -0.299974 0.150114)
			(stroke
				(width 0.1)
				(type default)
			)
			(layer "B.Fab")
		)
		(fp_line
			(start 0.299974 -0.150114)
			(end -0.299974 -0.150114)
			(stroke
				(width 0.1)
				(type default)
			)
			(layer "B.Fab")
		)
		(pad "1" smd rect
			(at 0.2667 0 90)
			(size 0.3048 0.381)
			(layers "B.Cu" "B.Mask" "B.Paste")
			(net "P0V8_PEX2")
		)
		(pad "2" smd rect
			(at -0.2667 0 90)
			(size 0.3048 0.381)
			(layers "B.Cu" "B.Mask" "B.Paste")
			(net "GND")
		)
	)
	(footprint ""
		(layer "B.Cu")
		(at 332.109826 -82.441034 -90)
		(property "Reference" "L14"
			(at 0 0 90)
			(layer "B.SilkS")
			(hide yes)
			(effects
				(font
					(size 1.27 1.27)
				)
				(justify mirror)
			)
		)
		(property "Value" ""
			(at 0 0 90)
			(layer "B.Fab")
			(effects
				(font
					(size 1.27 1.27)
				)
				(justify mirror)
			)
		)
		(duplicate_pad_numbers_are_jumpers no)
		(fp_line
			(start -1.27 0.5842)
			(end 1.27 0.5842)
			(stroke
				(width 0.1524)
				(type default)
			)
			(layer "B.SilkS")
		)
		(fp_line
			(start -1.27 0.5842)
			(end -1.27 -0.5842)
			(stroke
				(width 0.1524)
				(type default)
			)
			(layer "B.SilkS")
		)
		(fp_line
			(start 1.27 0.5842)
			(end 1.27 -0.5842)
			(stroke
				(width 0.1524)
				(type default)
			)
			(layer "B.SilkS")
		)
		(fp_line
			(start 1.27 -0.5588)
			(end 1.27 -0.5842)
			(stroke
				(width 0.1524)
				(type default)
			)
			(layer "B.SilkS")
		)
		(fp_line
			(start 1.27 -0.5842)
			(end -1.27 -0.5842)
			(stroke
				(width 0.1524)
				(type default)
			)
			(layer "B.SilkS")
		)
		(fp_line
			(start -0.9144 0.508)
			(end 0.9144 0.508)
			(stroke
				(width 0.1)
				(type default)
			)
			(layer "B.Fab")
		)
		(fp_line
			(start 0.9144 0.508)
			(end 0.9144 0.406654)
			(stroke
				(width 0.1)
				(type default)
			)
			(layer "B.Fab")
		)
		(fp_line
			(start 0.9144 0.406654)
			(end 1.194308 0.406654)
			(stroke
				(width 0.1)
				(type default)
			)
			(layer "B.Fab")
		)
		(fp_line
			(start 1.194308 0.406654)
			(end 1.194308 -0.406654)
			(stroke
				(width 0.1)
				(type default)
			)
			(layer "B.Fab")
		)
		(fp_line
			(start -1.1938 0.4064)
			(end -0.9144 0.4064)
			(stroke
				(width 0.1)
				(type default)
			)
			(layer "B.Fab")
		)
		(fp_line
			(start -0.9144 0.4064)
			(end -0.9144 0.508)
			(stroke
				(width 0.1)
				(type default)
			)
			(layer "B.Fab")
		)
		(fp_line
			(start -1.1938 -0.406654)
			(end -1.1938 0.4064)
			(stroke
				(width 0.1)
				(type default)
			)
			(layer "B.Fab")
		)
		(fp_line
			(start -0.9144 -0.406654)
			(end -1.1938 -0.406654)
			(stroke
				(width 0.1)
				(type default)
			)
			(layer "B.Fab")
		)
		(fp_line
			(start 0.9144 -0.406654)
			(end 0.9144 -0.508)
			(stroke
				(width 0.1)
				(type default)
			)
			(layer "B.Fab")
		)
		(fp_line
			(start 1.194308 -0.406654)
			(end 0.9144 -0.406654)
			(stroke
				(width 0.1)
				(type default)
			)
			(layer "B.Fab")
		)
		(fp_line
			(start -0.9144 -0.508)
			(end -0.9144 -0.406654)
			(stroke
				(width 0.1)
				(type default)
			)
			(layer "B.Fab")
		)
		(fp_line
			(start 0.9144 -0.508)
			(end -0.9144 -0.508)
			(stroke
				(width 0.1)
				(type default)
			)
			(layer "B.Fab")
		)
		(pad "1" smd rect
			(at 0.7366 0 180)
			(size 0.7112 0.8128)
			(layers "B.Cu" "B.Mask" "B.Paste")
			(net "P3V3")
		)
		(pad "2" smd rect
			(at -0.7366 0 180)
			(size 0.7112 0.8128)
			(layers "B.Cu" "B.Mask" "B.Paste")
			(net "P3V3_VDD_9ZXL0851_8_15")
		)
	)
	(footprint ""
		(layer "B.Cu")
		(at 54.899814 -301.599854 -90)
		(property "Reference" "C1217"
			(at 0 0 90)
			(layer "B.SilkS")
			(hide yes)
			(effects
				(font
					(size 1.27 1.27)
				)
				(justify mirror)
			)
		)
		(property "Value" ""
			(at 0 0 90)
			(layer "B.Fab")
			(effects
				(font
					(size 1.27 1.27)
				)
				(justify mirror)
			)
		)
		(duplicate_pad_numbers_are_jumpers no)
		(fp_line
			(start -0.299974 0.150114)
			(end 0.299974 0.150114)
			(stroke
				(width 0.1)
				(type default)
			)
			(layer "B.Fab")
		)
		(fp_line
			(start 0.299974 0.150114)
			(end 0.299974 -0.150114)
			(stroke
				(width 0.1)
				(type default)
			)
			(layer "B.Fab")
		)
		(fp_line
			(start -0.299974 -0.150114)
			(end -0.299974 0.150114)
			(stroke
				(width 0.1)
				(type default)
			)
			(layer "B.Fab")
		)
		(fp_line
			(start 0.299974 -0.150114)
			(end -0.299974 -0.150114)
			(stroke
				(width 0.1)
				(type default)
			)
			(layer "B.Fab")
		)
		(pad "1" smd rect
			(at 0.2667 0 90)
			(size 0.3048 0.381)
			(layers "B.Cu" "B.Mask" "B.Paste")
			(net "P0V8_SERDES_VDDA_PEX0")
		)
		(pad "2" smd rect
			(at -0.2667 0 90)
			(size 0.3048 0.381)
			(layers "B.Cu" "B.Mask" "B.Paste")
			(net "GND")
		)
	)
	(footprint ""
		(layer "B.Cu")
		(at 172.920406 -296.37482)
		(property "Reference" "C1363"
			(at 0 0 0)
			(layer "B.SilkS")
			(hide yes)
			(effects
				(font
					(size 1.27 1.27)
				)
				(justify mirror)
			)
		)
		(property "Value" ""
			(at 0 0 0)
			(layer "B.Fab")
			(effects
				(font
					(size 1.27 1.27)
				)
				(justify mirror)
			)
		)
		(duplicate_pad_numbers_are_jumpers no)
		(fp_line
			(start -0.299974 -0.150114)
			(end -0.299974 0.150114)
			(stroke
				(width 0.1)
				(type default)
			)
			(layer "B.Fab")
		)
		(fp_line
			(start -0.299974 0.150114)
			(end 0.299974 0.150114)
			(stroke
				(width 0.1)
				(type default)
			)
			(layer "B.Fab")
		)
		(fp_line
			(start 0.299974 -0.150114)
			(end -0.299974 -0.150114)
			(stroke
				(width 0.1)
				(type default)
			)
			(layer "B.Fab")
		)
		(fp_line
			(start 0.299974 0.150114)
			(end 0.299974 -0.150114)
			(stroke
				(width 0.1)
				(type default)
			)
			(layer "B.Fab")
		)
		(pad "1" smd rect
			(at 0.2667 0 180)
			(size 0.3048 0.381)
			(layers "B.Cu" "B.Mask" "B.Paste")
			(net "P0V8_PEX1")
		)
		(pad "2" smd rect
			(at -0.2667 0 180)
			(size 0.3048 0.381)
			(layers "B.Cu" "B.Mask" "B.Paste")
			(net "GND")
		)
	)
	(footprint ""
		(layer "B.Cu")
		(at 187.854844 -97.663 180)
		(property "Reference" "R175"
			(at 0 0 0)
			(layer "B.SilkS")
			(hide yes)
			(effects
				(font
					(size 1.27 1.27)
				)
				(justify mirror)
			)
		)
		(property "Value" ""
			(at 0 0 0)
			(layer "B.Fab")
			(effects
				(font
					(size 1.27 1.27)
				)
				(justify mirror)
			)
		)
		(duplicate_pad_numbers_are_jumpers no)
		(fp_line
			(start 0.7874 0.4064)
			(end 0.7874 -0.4064)
			(stroke
				(width 0.1524)
				(type default)
			)
			(layer "B.SilkS")
		)
		(fp_line
			(start 0.7874 -0.4064)
			(end -0.7874 -0.4064)
			(stroke
				(width 0.1524)
				(type default)
			)
			(layer "B.SilkS")
		)
		(fp_line
			(start -0.7874 0.4064)
			(end 0.7874 0.4064)
			(stroke
				(width 0.1524)
				(type default)
			)
			(layer "B.SilkS")
		)
		(fp_line
			(start -0.7874 -0.4064)
			(end -0.7874 0.4064)
			(stroke
				(width 0.1524)
				(type default)
			)
			(layer "B.SilkS")
		)
		(fp_line
			(start 0.67945 0.3048)
			(end 0.67945 -0.305054)
			(stroke
				(width 0.1)
				(type default)
			)
			(layer "B.Fab")
		)
		(fp_line
			(start 0.67945 -0.305054)
			(end 0.12065 -0.305054)
			(stroke
				(width 0.1)
				(type default)
			)
			(layer "B.Fab")
		)
		(fp_line
			(start 0.12065 0.3048)
			(end 0.67945 0.3048)
			(stroke
				(width 0.1)
				(type default)
			)
			(layer "B.Fab")
		)
		(fp_line
			(start 0.12065 0.2794)
			(end 0.12065 0.3048)
			(stroke
				(width 0.1)
				(type default)
			)
			(layer "B.Fab")
		)
		(fp_line
			(start 0.12065 -0.2794)
			(end -0.12065 -0.2794)
			(stroke
				(width 0.1)
				(type default)
			)
			(layer "B.Fab")
		)
		(fp_line
			(start 0.12065 -0.305054)
			(end 0.12065 -0.2794)
			(stroke
				(width 0.1)
				(type default)
			)
			(layer "B.Fab")
		)
		(fp_line
			(start -0.120396 0.3048)
			(end -0.120396 0.2794)
			(stroke
				(width 0.1)
				(type default)
			)
			(layer "B.Fab")
		)
		(fp_line
			(start -0.120396 0.2794)
			(end 0.12065 0.2794)
			(stroke
				(width 0.1)
				(type default)
			)
			(layer "B.Fab")
		)
		(fp_line
			(start -0.12065 -0.2794)
			(end -0.12065 -0.3048)
			(stroke
				(width 0.1)
				(type default)
			)
			(layer "B.Fab")
		)
		(fp_line
			(start -0.12065 -0.3048)
			(end -0.67945 -0.3048)
			(stroke
				(width 0.1)
				(type default)
			)
			(layer "B.Fab")
		)
		(fp_line
			(start -0.67945 0.3048)
			(end -0.120396 0.3048)
			(stroke
				(width 0.1)
				(type default)
			)
			(layer "B.Fab")
		)
		(fp_line
			(start -0.67945 -0.3048)
			(end -0.67945 0.3048)
			(stroke
				(width 0.1)
				(type default)
			)
			(layer "B.Fab")
		)
		(pad "1" smd circle
			(at 0.40005 0)
			(size 0 0)
			(layers "B.Cu" "B.Mask" "B.Paste")
			(net "PWRGD_NIC3_PWR_GOOD")
		)
		(pad "2" smd circle
			(at -0.40005 0)
			(size 0 0)
			(layers "B.Cu" "B.Mask" "B.Paste")
			(net "GND")
		)
	)
)
